# T6G (Grand Teton) — schematic netlist excerpt (pin names and nets, part order shuffled) for the footprints in the layout excerpt that follows; sources: Cadence DE-HDL packaged netlist, KiCad conversion of 04192023_DAF0TMB3IC0_F0TG_MB_C_brd_V02_OCP.brd

R437  Q_RES  2.2K 5% CHIP  pkg 0402LF  page 155 : A = PVDD18_S5_P0 ; B = IRQ_WAKE_N
PR6614  Q_RES  0 5% CHIP  pkg 0402LF  page 362 : A = NC_P0V9_RETIMER_CPU0_IMON8 ; B = GND

(kicad_pcb
	(version 20260206)
	(generator "pcbnew")
	(generator_version "10.0")
	(general
		(thickness 1.6)
		(legacy_teardrops no)
	)
	(paper "A4")
	(title_block
		(title "04192023_DAF0TMB3IC0_F0TG_MB_C_brd_V02_OCP.brd")
		(comment 1 "Grand Teton / footprints 4026-4027 of 8354")
	)
	(layers
		(0 "F.Cu" signal "TOP")
		(4 "In1.Cu" signal "GND")
		(6 "In2.Cu" signal "IN1")
		(8 "In3.Cu" signal "GND1")
		(10 "In4.Cu" signal "IN2")
		(12 "In5.Cu" signal "GND2")
		(14 "In6.Cu" signal "IN3")
		(16 "In7.Cu" signal "GND3")
		(18 "In8.Cu" signal "VCC")
		(20 "In9.Cu" signal "VCC1")
		(22 "In10.Cu" signal "GND4")
		(24 "In11.Cu" signal "IN4")
		(26 "In12.Cu" signal "GND5")
		(28 "In13.Cu" signal "IN5")
		(30 "In14.Cu" signal "GND6")
		(32 "In15.Cu" signal "IN6")
		(34 "In16.Cu" signal "GND7")
		(2 "B.Cu" signal "BOTTOM")
		(9 "F.Adhes" user "F.Adhesive")
		(11 "B.Adhes" user "B.Adhesive")
		(13 "F.Paste" user "Package Geometry/Pastemask Top")
		(15 "B.Paste" user "Package Geometry/Pastemask Bottom")
		(5 "F.SilkS" user "Ref Des/Silkscreen Top")
		(7 "B.SilkS" user "Ref Des/Silkscreen Bottom")
		(1 "F.Mask" user "Board Geometry/Soldermask Top")
		(3 "B.Mask" user "Board Geometry/Soldermask Bottom")
		(17 "Dwgs.User" user "User.Drawings")
		(19 "Cmts.User" user "User.Comments")
		(21 "Eco1.User" user "User.Eco1")
		(23 "Eco2.User" user "User.Eco2")
		(25 "Edge.Cuts" user "Board Geometry/Outline")
		(27 "Margin" user)
		(31 "F.CrtYd" user "Package Geometry/Place Bound Top")
		(29 "B.CrtYd" user "Package Geometry/Place Bound Bottom")
		(35 "F.Fab" user "Ref Des/Assembly Top")
		(33 "B.Fab" user "Ref Des/Assembly Bottom")
	)
	(footprint ""
		(layer "F.Cu")
		(at 447.792602 -418.96411 -90)
		(property "Reference" "PR6614"
			(at 0 0 270)
			(layer "F.SilkS")
			(hide yes)
			(effects
				(font
					(size 1.27 1.27)
				)
			)
		)
		(property "Value" ""
			(at 0 0 270)
			(layer "F.Fab")
			(effects
				(font
					(size 1.27 1.27)
				)
			)
		)
		(duplicate_pad_numbers_are_jumpers no)
		(fp_line
			(start -0.7874 0.4064)
			(end -0.7874 -0.4064)
			(stroke
				(width 0.1524)
				(type default)
			)
			(layer "F.SilkS")
		)
		(fp_line
			(start 0.7874 0.4064)
			(end -0.7874 0.4064)
			(stroke
				(width 0.1524)
				(type default)
			)
			(layer "F.SilkS")
		)
		(fp_line
			(start -0.7874 -0.4064)
			(end 0.7874 -0.4064)
			(stroke
				(width 0.1524)
				(type default)
			)
			(layer "F.SilkS")
		)
		(fp_line
			(start 0.7874 -0.4064)
			(end 0.7874 0.4064)
			(stroke
				(width 0.1524)
				(type default)
			)
			(layer "F.SilkS")
		)
		(fp_line
			(start -0.67945 0.3048)
			(end -0.67945 -0.305054)
			(stroke
				(width 0.1)
				(type default)
			)
			(layer "F.Fab")
		)
		(fp_line
			(start -0.12065 0.3048)
			(end -0.67945 0.3048)
			(stroke
				(width 0.1)
				(type default)
			)
			(layer "F.Fab")
		)
		(fp_line
			(start 0.120396 0.3048)
			(end 0.120396 0.2794)
			(stroke
				(width 0.1)
				(type default)
			)
			(layer "F.Fab")
		)
		(fp_line
			(start 0.67945 0.3048)
			(end 0.120396 0.3048)
			(stroke
				(width 0.1)
				(type default)
			)
			(layer "F.Fab")
		)
		(fp_line
			(start -0.12065 0.2794)
			(end -0.12065 0.3048)
			(stroke
				(width 0.1)
				(type default)
			)
			(layer "F.Fab")
		)
		(fp_line
			(start 0.120396 0.2794)
			(end -0.12065 0.2794)
			(stroke
				(width 0.1)
				(type default)
			)
			(layer "F.Fab")
		)
		(fp_line
			(start -0.12065 -0.2794)
			(end 0.12065 -0.2794)
			(stroke
				(width 0.1)
				(type default)
			)
			(layer "F.Fab")
		)
		(fp_line
			(start 0.12065 -0.2794)
			(end 0.12065 -0.3048)
			(stroke
				(width 0.1)
				(type default)
			)
			(layer "F.Fab")
		)
		(fp_line
			(start 0.12065 -0.3048)
			(end 0.67945 -0.3048)
			(stroke
				(width 0.1)
				(type default)
			)
			(layer "F.Fab")
		)
		(fp_line
			(start 0.67945 -0.3048)
			(end 0.67945 0.3048)
			(stroke
				(width 0.1)
				(type default)
			)
			(layer "F.Fab")
		)
		(fp_line
			(start -0.67945 -0.305054)
			(end -0.12065 -0.305054)
			(stroke
				(width 0.1)
				(type default)
			)
			(layer "F.Fab")
		)
		(fp_line
			(start -0.12065 -0.305054)
			(end -0.12065 -0.2794)
			(stroke
				(width 0.1)
				(type default)
			)
			(layer "F.Fab")
		)
		(pad "1" smd circle
			(at -0.40005 0 270)
			(size 0 0)
			(layers "F.Cu" "F.Mask" "F.Paste")
			(net "NC_P0V9_RETIMER_CPU0_IMON8")
		)
		(pad "2" smd circle
			(at 0.40005 0 270)
			(size 0 0)
			(layers "F.Cu" "F.Mask" "F.Paste")
			(net "GND")
		)
	)
	(footprint ""
		(layer "F.Cu")
		(at 393.363958 -323.643752 180)
		(property "Reference" "R437"
			(at 0 0 180)
			(layer "F.SilkS")
			(hide yes)
			(effects
				(font
					(size 1.27 1.27)
				)
			)
		)
		(property "Value" ""
			(at 0 0 180)
			(layer "F.Fab")
			(effects
				(font
					(size 1.27 1.27)
				)
			)
		)
		(duplicate_pad_numbers_are_jumpers no)
		(fp_line
			(start 0.7874 0.4064)
			(end -0.7874 0.4064)
			(stroke
				(width 0.1524)
				(type default)
			)
			(layer "F.SilkS")
		)
		(fp_line
			(start 0.7874 -0.4064)
			(end 0.7874 0.4064)
			(stroke
				(width 0.1524)
				(type default)
			)
			(layer "F.SilkS")
		)
		(fp_line
			(start -0.7874 0.4064)
			(end -0.7874 -0.4064)
			(stroke
				(width 0.1524)
				(type default)
			)
			(layer "F.SilkS")
		)
		(fp_line
			(start -0.7874 -0.4064)
			(end 0.7874 -0.4064)
			(stroke
				(width 0.1524)
				(type default)
			)
			(layer "F.SilkS")
		)
		(fp_line
			(start 0.67945 0.3048)
			(end 0.120396 0.3048)
			(stroke
				(width 0.1)
				(type default)
			)
			(layer "F.Fab")
		)
		(fp_line
			(start 0.67945 -0.3048)
			(end 0.67945 0.3048)
			(stroke
				(width 0.1)
				(type default)
			)
			(layer "F.Fab")
		)
		(fp_line
			(start 0.12065 -0.2794)
			(end 0.12065 -0.3048)
			(stroke
				(width 0.1)
				(type default)
			)
			(layer "F.Fab")
		)
		(fp_line
			(start 0.12065 -0.3048)
			(end 0.67945 -0.3048)
			(stroke
				(width 0.1)
				(type default)
			)
			(layer "F.Fab")
		)
		(fp_line
			(start 0.120396 0.3048)
			(end 0.120396 0.2794)
			(stroke
				(width 0.1)
				(type default)
			)
			(layer "F.Fab")
		)
		(fp_line
			(start 0.120396 0.2794)
			(end -0.12065 0.2794)
			(stroke
				(width 0.1)
				(type default)
			)
			(layer "F.Fab")
		)
		(fp_line
			(start -0.12065 0.3048)
			(end -0.67945 0.3048)
			(stroke
				(width 0.1)
				(type default)
			)
			(layer "F.Fab")
		)
		(fp_line
			(start -0.12065 0.2794)
			(end -0.12065 0.3048)
			(stroke
				(width 0.1)
				(type default)
			)
			(layer "F.Fab")
		)
		(fp_line
			(start -0.12065 -0.2794)
			(end 0.12065 -0.2794)
			(stroke
				(width 0.1)
				(type default)
			)
			(layer "F.Fab")
		)
		(fp_line
			(start -0.12065 -0.305054)
			(end -0.12065 -0.2794)
			(stroke
				(width 0.1)
				(type default)
			)
			(layer "F.Fab")
		)
		(fp_line
			(start -0.67945 0.3048)
			(end -0.67945 -0.305054)
			(stroke
				(width 0.1)
				(type default)
			)
			(layer "F.Fab")
		)
		(fp_line
			(start -0.67945 -0.305054)
			(end -0.12065 -0.305054)
			(stroke
				(width 0.1)
				(type default)
			)
			(layer "F.Fab")
		)
		(pad "1" smd circle
			(at -0.40005 0 180)
			(size 0 0)
			(layers "F.Cu" "F.Mask" "F.Paste")
			(net "PVDD18_S5_P0")
		)
		(pad "2" smd circle
			(at 0.40005 0 180)
			(size 0 0)
			(layers "F.Cu" "F.Mask" "F.Paste")
			(net "IRQ_WAKE_N")
		)
	)
)
